# S9S_MB_2U (Grand Teton) — schematic netlist excerpt (pin names and nets, part order shuffled) for the footprints in the layout excerpt that follows; sources: Cadence DE-HDL packaged netlist, KiCad conversion of 03242023_DA0F0TMBIJ0_F0T_Motherboard_J_brd_V01_OCP.brd

U17  74CBTLV3126PW  IC  pkg TSSOP14  page 132
  \1oe\  = PWRGD_PVNN_MAIN_CPU0
  \1a\  = JTAG_DBP_TMS
  \1b\  = JTAG_DBP_CPU_QS_GTL_TMS
  \2oe\  = PWRGD_PVNN_MAIN_CPU0
  \2a\  = JTAG_DBP_TDI
  \2b\  = JTAG_QS_MUX_GTL_TDI
  GND  = GND
  \3b\  = TP_74CB_B8
  \3a\  = PD_74CB_A9
  \3oe\  = PWRGD_PVNN_MAIN_CPU0
  \4b\  = JTAG_MUX_QS_GTL_TDO
  \4a\  = JTAG_DBP_TDO
  \4oe\  = PWRGD_PVNN_MAIN_CPU0
  VCC  = P3V3_AUX

PC565  Q_CAP  100NF 50V 10% X7R  pkg C0402  page 285 : A = SW_PVCCIN_CPU1_BOOT1_R ; B = SW_PVCCIN_CPU1_BOOTR1

(kicad_pcb
	(version 20260206)
	(generator "pcbnew")
	(generator_version "10.0")
	(general
		(thickness 1.6)
		(legacy_teardrops no)
	)
	(paper "A4")
	(title_block
		(title "03242023_DA0F0TMBIJ0_F0T_Motherboard_J_brd_V01_OCP.brd")
		(comment 1 "Grand Teton / footprints 264-265 of 6105")
	)
	(layers
		(0 "F.Cu" signal "TOP")
		(4 "In1.Cu" signal "GND")
		(6 "In2.Cu" signal "IN1")
		(8 "In3.Cu" signal "GND1")
		(10 "In4.Cu" signal "IN2")
		(12 "In5.Cu" signal "GND2")
		(14 "In6.Cu" signal "IN3")
		(16 "In7.Cu" signal "GND3")
		(18 "In8.Cu" signal "VCC")
		(20 "In9.Cu" signal "VCC1")
		(22 "In10.Cu" signal "GND4")
		(24 "In11.Cu" signal "IN4")
		(26 "In12.Cu" signal "GND5")
		(28 "In13.Cu" signal "IN5")
		(30 "In14.Cu" signal "GND6")
		(32 "In15.Cu" signal "IN6")
		(34 "In16.Cu" signal "GND7")
		(2 "B.Cu" signal "BOTTOM")
		(9 "F.Adhes" user "F.Adhesive")
		(11 "B.Adhes" user "B.Adhesive")
		(13 "F.Paste" user "Package Geometry/Pastemask Top")
		(15 "B.Paste" user "Package Geometry/Pastemask Bottom")
		(5 "F.SilkS" user "Ref Des/Silkscreen Top")
		(7 "B.SilkS" user "Ref Des/Silkscreen Bottom")
		(1 "F.Mask" user "Board Geometry/Soldermask Top")
		(3 "B.Mask" user "Board Geometry/Soldermask Bottom")
		(17 "Dwgs.User" user "User.Drawings")
		(19 "Cmts.User" user "User.Comments")
		(21 "Eco1.User" user "User.Eco1")
		(23 "Eco2.User" user "User.Eco2")
		(25 "Edge.Cuts" user "Board Geometry/Outline")
		(27 "Margin" user)
		(31 "F.CrtYd" user "Package Geometry/Place Bound Top")
		(29 "B.CrtYd" user "Package Geometry/Place Bound Bottom")
		(35 "F.Fab" user "Ref Des/Assembly Top")
		(33 "B.Fab" user "Ref Des/Assembly Bottom")
	)
	(footprint ""
		(layer "F.Cu")
		(at 99.067366 -338.180172 -90)
		(property "Reference" "PC565"
			(at 0 0 270)
			(layer "F.SilkS")
			(hide yes)
			(effects
				(font
					(size 1.27 1.27)
				)
			)
		)
		(property "Value" ""
			(at 0 0 270)
			(layer "F.Fab")
			(effects
				(font
					(size 1.27 1.27)
				)
			)
		)
		(duplicate_pad_numbers_are_jumpers no)
		(fp_line
			(start -0.7874 0.4064)
			(end -0.7874 -0.4064)
			(stroke
				(width 0.1524)
				(type default)
			)
			(layer "F.SilkS")
		)
		(fp_line
			(start 0.7874 0.4064)
			(end -0.7874 0.4064)
			(stroke
				(width 0.1524)
				(type default)
			)
			(layer "F.SilkS")
		)
		(fp_line
			(start -0.7874 -0.4064)
			(end 0.7874 -0.4064)
			(stroke
				(width 0.1524)
				(type default)
			)
			(layer "F.SilkS")
		)
		(fp_line
			(start 0.7874 -0.4064)
			(end 0.7874 0.4064)
			(stroke
				(width 0.1524)
				(type default)
			)
			(layer "F.SilkS")
		)
		(fp_line
			(start -0.67945 0.3048)
			(end -0.67945 -0.305054)
			(stroke
				(width 0.1)
				(type default)
			)
			(layer "F.Fab")
		)
		(fp_line
			(start -0.12065 0.3048)
			(end -0.67945 0.3048)
			(stroke
				(width 0.1)
				(type default)
			)
			(layer "F.Fab")
		)
		(fp_line
			(start 0.120396 0.3048)
			(end 0.120396 0.2794)
			(stroke
				(width 0.1)
				(type default)
			)
			(layer "F.Fab")
		)
		(fp_line
			(start 0.67945 0.3048)
			(end 0.120396 0.3048)
			(stroke
				(width 0.1)
				(type default)
			)
			(layer "F.Fab")
		)
		(fp_line
			(start -0.12065 0.2794)
			(end -0.12065 0.3048)
			(stroke
				(width 0.1)
				(type default)
			)
			(layer "F.Fab")
		)
		(fp_line
			(start 0.120396 0.2794)
			(end -0.12065 0.2794)
			(stroke
				(width 0.1)
				(type default)
			)
			(layer "F.Fab")
		)
		(fp_line
			(start -0.12065 -0.2794)
			(end 0.12065 -0.2794)
			(stroke
				(width 0.1)
				(type default)
			)
			(layer "F.Fab")
		)
		(fp_line
			(start 0.12065 -0.2794)
			(end 0.12065 -0.3048)
			(stroke
				(width 0.1)
				(type default)
			)
			(layer "F.Fab")
		)
		(fp_line
			(start 0.12065 -0.3048)
			(end 0.67945 -0.3048)
			(stroke
				(width 0.1)
				(type default)
			)
			(layer "F.Fab")
		)
		(fp_line
			(start 0.67945 -0.3048)
			(end 0.67945 0.3048)
			(stroke
				(width 0.1)
				(type default)
			)
			(layer "F.Fab")
		)
		(fp_line
			(start -0.67945 -0.305054)
			(end -0.12065 -0.305054)
			(stroke
				(width 0.1)
				(type default)
			)
			(layer "F.Fab")
		)
		(fp_line
			(start -0.12065 -0.305054)
			(end -0.12065 -0.2794)
			(stroke
				(width 0.1)
				(type default)
			)
			(layer "F.Fab")
		)
		(pad "1" smd circle
			(at -0.40005 0 270)
			(size 0 0)
			(layers "F.Cu" "F.Mask" "F.Paste")
			(net "SW_PVCCIN_CPU1_BOOT1_R")
		)
		(pad "2" smd circle
			(at 0.40005 0 270)
			(size 0 0)
			(layers "F.Cu" "F.Mask" "F.Paste")
			(net "SW_PVCCIN_CPU1_BOOTR1")
		)
	)
	(footprint ""
		(layer "F.Cu")
		(at 367.762282 -58.533792)
		(property "Reference" "U17"
			(at -2.032 -3.27533 0)
			(unlocked yes)
			(layer "F.SilkS")
			(effects
				(font
					(size 0.7874 0.5842)
					(thickness 0.1524)
				)
				(justify left)
			)
		)
		(property "Value" ""
			(at 0 0 0)
			(layer "F.Fab")
			(effects
				(font
					(size 1.27 1.27)
				)
			)
		)
		(duplicate_pad_numbers_are_jumpers no)
		(fp_line
			(start -2.0066 -2.5527)
			(end -0.5715 -2.5527)
			(stroke
				(width 0.1524)
				(type default)
			)
			(layer "F.SilkS")
		)
		(fp_line
			(start -2.0066 2.5527)
			(end -2.0066 -2.5527)
			(stroke
				(width 0.1524)
				(type default)
			)
			(layer "F.SilkS")
		)
		(fp_line
			(start -0.5715 -2.5527)
			(end 0 -1.9812)
			(stroke
				(width 0.1524)
				(type default)
			)
			(layer "F.SilkS")
		)
		(fp_line
			(start 0 -1.9812)
			(end 0.5715 -2.5527)
			(stroke
				(width 0.1524)
				(type default)
			)
			(layer "F.SilkS")
		)
		(fp_line
			(start 0.5715 -2.5527)
			(end 2.0066 -2.5527)
			(stroke
				(width 0.1524)
				(type default)
			)
			(layer "F.SilkS")
		)
		(fp_line
			(start 2.0066 -2.5527)
			(end 2.0066 2.5527)
			(stroke
				(width 0.1524)
				(type default)
			)
			(layer "F.SilkS")
		)
		(fp_line
			(start 2.0066 2.5527)
			(end -2.0066 2.5527)
			(stroke
				(width 0.1524)
				(type default)
			)
			(layer "F.SilkS")
		)
		(fp_poly
			(pts
				(xy -4.36372 -2.233168) (xy -3.81 -1.905) (xy -4.36372 -1.608328)
			)
			(stroke
				(width 0)
				(type default)
			)
			(fill yes)
			(layer "F.SilkS")
		)
		(fp_line
			(start -2.249932 -2.549906)
			(end 2.249932 -2.549906)
			(stroke
				(width 0.1)
				(type default)
			)
			(layer "F.Fab")
		)
		(fp_line
			(start -2.249932 2.549906)
			(end -2.249932 -2.549906)
			(stroke
				(width 0.1)
				(type default)
			)
			(layer "F.Fab")
		)
		(fp_line
			(start 2.249932 -2.549906)
			(end 2.249932 2.549906)
			(stroke
				(width 0.1)
				(type default)
			)
			(layer "F.Fab")
		)
		(fp_line
			(start 2.249932 2.549906)
			(end -2.249932 2.549906)
			(stroke
				(width 0.1)
				(type default)
			)
			(layer "F.Fab")
		)
		(fp_poly
			(pts
				(xy -4.36372 -1.608328) (xy -4.36372 -2.233168) (xy -3.81 -1.905)
			)
			(stroke
				(width 0)
				(type default)
			)
			(fill yes)
			(layer "F.Fab")
		)
		(pad "1" smd rect
			(at -2.921 -1.949958 270)
			(size 0.3556 1.4986)
			(layers "F.Cu" "F.Mask" "F.Paste")
			(net "PWRGD_PVNN_MAIN_CPU0")
		)
		(pad "2" smd rect
			(at -2.921 -1.299972 270)
			(size 0.3556 1.4986)
			(layers "F.Cu" "F.Mask" "F.Paste")
			(net "JTAG_DBP_TMS")
		)
		(pad "3" smd rect
			(at -2.921 -0.649986 270)
			(size 0.3556 1.4986)
			(layers "F.Cu" "F.Mask" "F.Paste")
			(net "JTAG_DBP_CPU_QS_GTL_TMS")
		)
		(pad "4" smd rect
			(at -2.921 0 270)
			(size 0.3556 1.4986)
			(layers "F.Cu" "F.Mask" "F.Paste")
			(net "PWRGD_PVNN_MAIN_CPU0")
		)
		(pad "5" smd rect
			(at -2.921 0.649986 270)
			(size 0.3556 1.4986)
			(layers "F.Cu" "F.Mask" "F.Paste")
			(net "JTAG_DBP_TDI")
		)
		(pad "6" smd rect
			(at -2.921 1.299972 270)
			(size 0.3556 1.4986)
			(layers "F.Cu" "F.Mask" "F.Paste")
			(net "JTAG_QS_MUX_GTL_TDI")
		)
		(pad "7" smd rect
			(at -2.921 1.949958 270)
			(size 0.3556 1.4986)
			(layers "F.Cu" "F.Mask" "F.Paste")
			(net "GND")
		)
		(pad "8" smd rect
			(at 2.921 1.949958 270)
			(size 0.3556 1.4986)
			(layers "F.Cu" "F.Mask" "F.Paste")
			(net "TP_74CB_B8")
		)
		(pad "9" smd rect
			(at 2.921 1.299972 270)
			(size 0.3556 1.4986)
			(layers "F.Cu" "F.Mask" "F.Paste")
			(net "PD_74CB_A9")
		)
		(pad "10" smd rect
			(at 2.921 0.649986 270)
			(size 0.3556 1.4986)
			(layers "F.Cu" "F.Mask" "F.Paste")
			(net "PWRGD_PVNN_MAIN_CPU0")
		)
		(pad "11" smd rect
			(at 2.921 0 270)
			(size 0.3556 1.4986)
			(layers "F.Cu" "F.Mask" "F.Paste")
			(net "JTAG_MUX_QS_GTL_TDO")
		)
		(pad "12" smd rect
			(at 2.921 -0.649986 270)
			(size 0.3556 1.4986)
			(layers "F.Cu" "F.Mask" "F.Paste")
			(net "JTAG_DBP_TDO")
		)
		(pad "13" smd rect
			(at 2.921 -1.299972 270)
			(size 0.3556 1.4986)
			(layers "F.Cu" "F.Mask" "F.Paste")
			(net "PWRGD_PVNN_MAIN_CPU0")
		)
		(pad "14" smd rect
			(at 2.921 -1.949958 270)
			(size 0.3556 1.4986)
			(layers "F.Cu" "F.Mask" "F.Paste")
			(net "P3V3_AUX")
		)
	)
)
